(kicad_pcb
	(version 20260206)
	(generator "pcbnew")
	(generator_version "10.0")
	(general
		(thickness 1.6)
		(legacy_teardrops no)
	)
	(paper "A4")
	(title_block
		(title "04192023_DAF0TMB3IC0_F0TG_MB_C_brd_V02_OCP.brd")
		(comment 1 "Grand Teton / footprint 703 of 8354 (J106), pads 1-48 of 48")
	)
	(layers
		(0 "F.Cu" signal "TOP")
		(4 "In1.Cu" signal "GND")
		(6 "In2.Cu" signal "IN1")
		(8 "In3.Cu" signal "GND1")
		(10 "In4.Cu" signal "IN2")
		(12 "In5.Cu" signal "GND2")
		(14 "In6.Cu" signal "IN3")
		(16 "In7.Cu" signal "GND3")
		(18 "In8.Cu" signal "VCC")
		(20 "In9.Cu" signal "VCC1")
		(22 "In10.Cu" signal "GND4")
		(24 "In11.Cu" signal "IN4")
		(26 "In12.Cu" signal "GND5")
		(28 "In13.Cu" signal "IN5")
		(30 "In14.Cu" signal "GND6")
		(32 "In15.Cu" signal "IN6")
		(34 "In16.Cu" signal "GND7")
		(2 "B.Cu" signal "BOTTOM")
		(9 "F.Adhes" user "F.Adhesive")
		(11 "B.Adhes" user "B.Adhesive")
		(13 "F.Paste" user "Package Geometry/Pastemask Top")
		(15 "B.Paste" user "Package Geometry/Pastemask Bottom")
		(5 "F.SilkS" user "Ref Des/Silkscreen Top")
		(7 "B.SilkS" user "Ref Des/Silkscreen Bottom")
		(1 "F.Mask" user "Board Geometry/Soldermask Top")
		(3 "B.Mask" user "Board Geometry/Soldermask Bottom")
		(17 "Dwgs.User" user "User.Drawings")
		(19 "Cmts.User" user "User.Comments")
		(21 "Eco1.User" user "User.Eco1")
		(23 "Eco2.User" user "User.Eco2")
		(25 "Edge.Cuts" user "Board Geometry/Outline")
		(27 "Margin" user)
		(31 "F.CrtYd" user "Package Geometry/Place Bound Top")
		(29 "B.CrtYd" user "Package Geometry/Place Bound Bottom")
		(35 "F.Fab" user "Ref Des/Assembly Top")
		(33 "B.Fab" user "Ref Des/Assembly Bottom")
	)
	(footprint ""
		(layer "F.Cu")
		(at 381.749808 -440.489848)
		(property "Reference" "J106"
			(at -7.604506 17.991328 0)
			(unlocked yes)
			(layer "F.SilkS")
			(effects
				(font
					(size 0.7874 0.5842)
					(thickness 0.1524)
				)
				(justify left)
			)
		)
		(property "Value" ""
			(at 0 0 0)
			(layer "F.Fab")
			(effects
				(font
					(size 1.27 1.27)
				)
			)
		)
		(duplicate_pad_numbers_are_jumpers no)
		(pad "A1" thru_hole rect
			(at 0 0 180)
			(size 0.766318 0.766318)
			(drill 0.359918)
			(layers "*.Cu" "*.Mask")
			(remove_unused_layers no)
			(net "PRSNT_CABLE_SWB_B1_N")
			(clearance 0.0508)
			(thermal_gap 0.0508)
			(padstack
				(mode front_inner_back)
				(layer "Inner"
					(shape circle)
					(size 0.766318 0.766318)
					(clearance 0.0508)
				)
				(layer "B.Cu"
					(shape rect)
					(size 0.766318 0.766318)
					(clearance 0.0508)
				)
			)
		)
		(pad "A2" thru_hole circle
			(at 1.999996 0.199898 180)
			(size 0.906272 0.906272)
			(drill 0.499872)
			(layers "*.Cu" "*.Mask")
			(remove_unused_layers no)
			(net "GND")
			(clearance 0.0508)
			(thermal_gap 0.0508)
		)
		(pad "A3" thru_hole circle
			(at 3.999992 0 180)
			(size 0.766318 0.766318)
			(drill 0.359918)
			(layers "*.Cu" "*.Mask")
			(remove_unused_layers no)
			(net "FM_SWB_PWRGD")
			(clearance 0.0508)
			(thermal_gap 0.0508)
		)
		(pad "A4" thru_hole circle
			(at 5.999988 0.199898 180)
			(size 0.906272 0.906272)
			(drill 0.499872)
			(layers "*.Cu" "*.Mask")
			(remove_unused_layers no)
			(net "GND")
			(clearance 0.0508)
			(thermal_gap 0.0508)
		)
		(pad "A5" thru_hole circle
			(at 7.999984 0 180)
			(size 0.766318 0.766318)
			(drill 0.359918)
			(layers "*.Cu" "*.Mask")
			(remove_unused_layers no)
			(net "NC_J106_A5")
			(clearance 0.0508)
			(thermal_gap 0.0508)
		)
		(pad "A6" thru_hole circle
			(at 9.99998 0.199898 180)
			(size 0.906272 0.906272)
			(drill 0.499872)
			(layers "*.Cu" "*.Mask")
			(remove_unused_layers no)
			(net "GND")
			(clearance 0.0508)
			(thermal_gap 0.0508)
		)
		(pad "A7" thru_hole circle
			(at 11.999976 0 180)
			(size 0.766318 0.766318)
			(drill 0.359918)
			(layers "*.Cu" "*.Mask")
			(remove_unused_layers no)
			(net "PRSNT_CABLE_GPU_A1_N")
			(clearance 0.0508)
			(thermal_gap 0.0508)
		)
		(pad "A8" thru_hole circle
			(at 13.999972 0.199898 180)
			(size 0.906272 0.906272)
			(drill 0.499872)
			(layers "*.Cu" "*.Mask")
			(remove_unused_layers no)
			(net "GND")
			(clearance 0.0508)
			(thermal_gap 0.0508)
		)
		(pad "B1" thru_hole circle
			(at 0 1.199896 180)
			(size 0.906272 0.906272)
			(drill 0.499872)
			(layers "*.Cu" "*.Mask")
			(remove_unused_layers no)
			(net "GND")
			(clearance 0.0508)
			(thermal_gap 0.0508)
		)
		(pad "B3" thru_hole circle
			(at 3.999992 1.199896 180)
			(size 0.906272 0.906272)
			(drill 0.499872)
			(layers "*.Cu" "*.Mask")
			(remove_unused_layers no)
			(net "GND")
			(clearance 0.0508)
			(thermal_gap 0.0508)
		)
		(pad "B5" thru_hole circle
			(at 7.999984 1.199896 180)
			(size 0.906272 0.906272)
			(drill 0.499872)
			(layers "*.Cu" "*.Mask")
			(remove_unused_layers no)
			(net "GND")
			(clearance 0.0508)
			(thermal_gap 0.0508)
		)
		(pad "B7" thru_hole circle
			(at 11.999976 1.199896 180)
			(size 0.906272 0.906272)
			(drill 0.499872)
			(layers "*.Cu" "*.Mask")
			(remove_unused_layers no)
			(net "GND")
			(clearance 0.0508)
			(thermal_gap 0.0508)
		)
		(pad "D2" thru_hole circle
			(at 1.999996 3.800094 180)
			(size 0.906272 0.906272)
			(drill 0.499872)
			(layers "*.Cu" "*.Mask")
			(remove_unused_layers no)
			(net "GND")
			(clearance 0.0508)
			(thermal_gap 0.0508)
		)
		(pad "D4" thru_hole circle
			(at 5.999988 3.800094 180)
			(size 0.906272 0.906272)
			(drill 0.499872)
			(layers "*.Cu" "*.Mask")
			(remove_unused_layers no)
			(net "GND")
			(clearance 0.0508)
			(thermal_gap 0.0508)
		)
		(pad "D6" thru_hole circle
			(at 9.99998 3.800094 180)
			(size 0.906272 0.906272)
			(drill 0.499872)
			(layers "*.Cu" "*.Mask")
			(remove_unused_layers no)
			(net "GND")
			(clearance 0.0508)
			(thermal_gap 0.0508)
		)
		(pad "D8" thru_hole circle
			(at 13.999972 3.800094 180)
			(size 0.906272 0.906272)
			(drill 0.499872)
			(layers "*.Cu" "*.Mask")
			(remove_unused_layers no)
			(net "GND")
			(clearance 0.0508)
			(thermal_gap 0.0508)
		)
		(pad "E1" thru_hole circle
			(at 0 4.800092 180)
			(size 0.906272 0.906272)
			(drill 0.499872)
			(layers "*.Cu" "*.Mask")
			(remove_unused_layers no)
			(net "GND")
			(clearance 0.0508)
			(thermal_gap 0.0508)
		)
		(pad "E3" thru_hole circle
			(at 3.999992 4.800092 180)
			(size 0.906272 0.906272)
			(drill 0.499872)
			(layers "*.Cu" "*.Mask")
			(remove_unused_layers no)
			(net "GND")
			(clearance 0.0508)
			(thermal_gap 0.0508)
		)
		(pad "E5" thru_hole circle
			(at 7.999984 4.800092 180)
			(size 0.906272 0.906272)
			(drill 0.499872)
			(layers "*.Cu" "*.Mask")
			(remove_unused_layers no)
			(net "GND")
			(clearance 0.0508)
			(thermal_gap 0.0508)
		)
		(pad "E7" thru_hole circle
			(at 11.999976 4.800092 180)
			(size 0.906272 0.906272)
			(drill 0.499872)
			(layers "*.Cu" "*.Mask")
			(remove_unused_layers no)
			(net "GND")
			(clearance 0.0508)
			(thermal_gap 0.0508)
		)
		(pad "G2" thru_hole circle
			(at 1.999996 7.400036 180)
			(size 0.906272 0.906272)
			(drill 0.499872)
			(layers "*.Cu" "*.Mask")
			(remove_unused_layers no)
			(net "GND")
			(clearance 0.0508)
			(thermal_gap 0.0508)
		)
		(pad "G4" thru_hole circle
			(at 5.999988 7.400036 180)
			(size 0.906272 0.906272)
			(drill 0.499872)
			(layers "*.Cu" "*.Mask")
			(remove_unused_layers no)
			(net "GND")
			(clearance 0.0508)
			(thermal_gap 0.0508)
		)
		(pad "G6" thru_hole circle
			(at 9.99998 7.400036 180)
			(size 0.906272 0.906272)
			(drill 0.499872)
			(layers "*.Cu" "*.Mask")
			(remove_unused_layers no)
			(net "GND")
			(clearance 0.0508)
			(thermal_gap 0.0508)
		)
		(pad "G8" thru_hole circle
			(at 13.999972 7.400036 180)
			(size 0.906272 0.906272)
			(drill 0.499872)
			(layers "*.Cu" "*.Mask")
			(remove_unused_layers no)
			(net "GND")
			(clearance 0.0508)
			(thermal_gap 0.0508)
		)
		(pad "H1" thru_hole circle
			(at 0 8.400034 180)
			(size 0.906272 0.906272)
			(drill 0.499872)
			(layers "*.Cu" "*.Mask")
			(remove_unused_layers no)
			(net "GND")
			(clearance 0.0508)
			(thermal_gap 0.0508)
		)
		(pad "H3" thru_hole circle
			(at 3.999992 8.400034 180)
			(size 0.906272 0.906272)
			(drill 0.499872)
			(layers "*.Cu" "*.Mask")
			(remove_unused_layers no)
			(net "GND")
			(clearance 0.0508)
			(thermal_gap 0.0508)
		)
		(pad "H5" thru_hole circle
			(at 7.999984 8.400034 180)
			(size 0.906272 0.906272)
			(drill 0.499872)
			(layers "*.Cu" "*.Mask")
			(remove_unused_layers no)
			(net "GND")
			(clearance 0.0508)
			(thermal_gap 0.0508)
		)
		(pad "H7" thru_hole circle
			(at 11.999976 8.400034 180)
			(size 0.906272 0.906272)
			(drill 0.499872)
			(layers "*.Cu" "*.Mask")
			(remove_unused_layers no)
			(net "GND")
			(clearance 0.0508)
			(thermal_gap 0.0508)
		)
		(pad "J2" thru_hole circle
			(at 1.999996 10.999978 180)
			(size 0.906272 0.906272)
			(drill 0.499872)
			(layers "*.Cu" "*.Mask")
			(remove_unused_layers no)
			(net "GND")
			(clearance 0.0508)
			(thermal_gap 0.0508)
		)
		(pad "J4" thru_hole circle
			(at 5.999988 10.999978 180)
			(size 0.906272 0.906272)
			(drill 0.499872)
			(layers "*.Cu" "*.Mask")
			(remove_unused_layers no)
			(net "GND")
			(clearance 0.0508)
			(thermal_gap 0.0508)
		)
		(pad "J6" thru_hole circle
			(at 9.99998 10.999978 180)
			(size 0.906272 0.906272)
			(drill 0.499872)
			(layers "*.Cu" "*.Mask")
			(remove_unused_layers no)
			(net "GND")
			(clearance 0.0508)
			(thermal_gap 0.0508)
		)
		(pad "J8" thru_hole circle
			(at 13.999972 10.999978 180)
			(size 0.906272 0.906272)
			(drill 0.499872)
			(layers "*.Cu" "*.Mask")
			(remove_unused_layers no)
			(net "GND")
			(clearance 0.0508)
			(thermal_gap 0.0508)
		)
		(pad "K1" thru_hole circle
			(at 0 11.999976 180)
			(size 0.906272 0.906272)
			(drill 0.499872)
			(layers "*.Cu" "*.Mask")
			(remove_unused_layers no)
			(net "GND")
			(clearance 0.0508)
			(thermal_gap 0.0508)
		)
		(pad "K3" thru_hole circle
			(at 3.999992 11.999976 180)
			(size 0.906272 0.906272)
			(drill 0.499872)
			(layers "*.Cu" "*.Mask")
			(remove_unused_layers no)
			(net "GND")
			(clearance 0.0508)
			(thermal_gap 0.0508)
		)
		(pad "K5" thru_hole circle
			(at 7.999984 11.999976 180)
			(size 0.906272 0.906272)
			(drill 0.499872)
			(layers "*.Cu" "*.Mask")
			(remove_unused_layers no)
			(net "GND")
			(clearance 0.0508)
			(thermal_gap 0.0508)
		)
		(pad "K7" thru_hole circle
			(at 11.999976 11.999976 180)
			(size 0.906272 0.906272)
			(drill 0.499872)
			(layers "*.Cu" "*.Mask")
			(remove_unused_layers no)
			(net "GND")
			(clearance 0.0508)
			(thermal_gap 0.0508)
		)
		(pad "M2" thru_hole circle
			(at 1.999996 14.59992 180)
			(size 0.906272 0.906272)
			(drill 0.499872)
			(layers "*.Cu" "*.Mask")
			(remove_unused_layers no)
			(net "GND")
			(clearance 0.0508)
			(thermal_gap 0.0508)
		)
		(pad "M4" thru_hole circle
			(at 5.999988 14.59992 180)
			(size 0.906272 0.906272)
			(drill 0.499872)
			(layers "*.Cu" "*.Mask")
			(remove_unused_layers no)
			(net "GND")
			(clearance 0.0508)
			(thermal_gap 0.0508)
		)
		(pad "M6" thru_hole circle
			(at 9.99998 14.59992 180)
			(size 0.906272 0.906272)
			(drill 0.499872)
			(layers "*.Cu" "*.Mask")
			(remove_unused_layers no)
			(net "GND")
			(clearance 0.0508)
			(thermal_gap 0.0508)
		)
		(pad "M8" thru_hole circle
			(at 13.999972 14.59992 180)
			(size 0.906272 0.906272)
			(drill 0.499872)
			(layers "*.Cu" "*.Mask")
			(remove_unused_layers no)
			(net "GND")
			(clearance 0.0508)
			(thermal_gap 0.0508)
		)
		(pad "N1" thru_hole circle
			(at 0 15.599918 180)
			(size 0.906272 0.906272)
			(drill 0.499872)
			(layers "*.Cu" "*.Mask")
			(remove_unused_layers no)
			(net "GND")
			(clearance 0.0508)
			(thermal_gap 0.0508)
		)
		(pad "N2" thru_hole circle
			(at 1.999996 15.80007 180)
			(size 0.766318 0.766318)
			(drill 0.359918)
			(layers "*.Cu" "*.Mask")
			(remove_unused_layers no)
			(net "I3C_BMC_SWB_BUF_SDA")
			(clearance 0.0508)
			(thermal_gap 0.0508)
		)
		(pad "N3" thru_hole circle
			(at 3.999992 15.599918 180)
			(size 0.906272 0.906272)
			(drill 0.499872)
			(layers "*.Cu" "*.Mask")
			(remove_unused_layers no)
			(net "GND")
			(clearance 0.0508)
			(thermal_gap 0.0508)
		)
		(pad "N4" thru_hole circle
			(at 5.999988 15.80007 180)
			(size 0.766318 0.766318)
			(drill 0.359918)
			(layers "*.Cu" "*.Mask")
			(remove_unused_layers no)
			(net "I3C_BMC_SWB_BUF_SCL")
			(clearance 0.0508)
			(thermal_gap 0.0508)
		)
		(pad "N5" thru_hole circle
			(at 7.999984 15.599918 180)
			(size 0.906272 0.906272)
			(drill 0.499872)
			(layers "*.Cu" "*.Mask")
			(remove_unused_layers no)
			(net "GND")
			(clearance 0.0508)
			(thermal_gap 0.0508)
		)
		(pad "N6" thru_hole circle
			(at 9.99998 15.80007 180)
			(size 0.766318 0.766318)
			(drill 0.359918)
			(layers "*.Cu" "*.Mask")
			(remove_unused_layers no)
			(net "UART_BMC_BIC_RX")
			(clearance 0.0508)
			(thermal_gap 0.0508)
		)
		(pad "N7" thru_hole circle
			(at 11.999976 15.599918 180)
			(size 0.906272 0.906272)
			(drill 0.499872)
			(layers "*.Cu" "*.Mask")
			(remove_unused_layers no)
			(net "GND")
			(clearance 0.0508)
			(thermal_gap 0.0508)
		)
		(pad "N8" thru_hole circle
			(at 13.999972 15.80007 180)
			(size 0.766318 0.766318)
			(drill 0.359918)
			(layers "*.Cu" "*.Mask")
			(remove_unused_layers no)
			(net "UART_BMC_BIC_TX")
			(clearance 0.0508)
			(thermal_gap 0.0508)
		)
	)
)
